# S9S_MB_2U (Grand Teton) — schematic netlist excerpt (pin names and nets, part order shuffled) for the footprints in the layout excerpt that follows; sources: Cadence DE-HDL packaged netlist, KiCad conversion of 03242023_DA0F0TMBIJ0_F0T_Motherboard_J_brd_V01_OCP.brd

R3624  Q_RES  4.7K 1% CHIP  pkg 0402LF  page 172 : A = P3V3_AUX ; B = INA230_5_A1
R627  Q_RES  1K 1% EMPTY  pkg 0402LF  page 127 : A = P3V3_AUX ; B = PD_PIROM_CPU1_ADDR1

(kicad_pcb
	(version 20260206)
	(generator "pcbnew")
	(generator_version "10.0")
	(general
		(thickness 1.6)
		(legacy_teardrops no)
	)
	(paper "A4")
	(title_block
		(title "03242023_DA0F0TMBIJ0_F0T_Motherboard_J_brd_V01_OCP.brd")
		(comment 1 "Grand Teton / footprints 1652-1653 of 6105")
	)
	(layers
		(0 "F.Cu" signal "TOP")
		(4 "In1.Cu" signal "GND")
		(6 "In2.Cu" signal "IN1")
		(8 "In3.Cu" signal "GND1")
		(10 "In4.Cu" signal "IN2")
		(12 "In5.Cu" signal "GND2")
		(14 "In6.Cu" signal "IN3")
		(16 "In7.Cu" signal "GND3")
		(18 "In8.Cu" signal "VCC")
		(20 "In9.Cu" signal "VCC1")
		(22 "In10.Cu" signal "GND4")
		(24 "In11.Cu" signal "IN4")
		(26 "In12.Cu" signal "GND5")
		(28 "In13.Cu" signal "IN5")
		(30 "In14.Cu" signal "GND6")
		(32 "In15.Cu" signal "IN6")
		(34 "In16.Cu" signal "GND7")
		(2 "B.Cu" signal "BOTTOM")
		(9 "F.Adhes" user "F.Adhesive")
		(11 "B.Adhes" user "B.Adhesive")
		(13 "F.Paste" user "Package Geometry/Pastemask Top")
		(15 "B.Paste" user "Package Geometry/Pastemask Bottom")
		(5 "F.SilkS" user "Ref Des/Silkscreen Top")
		(7 "B.SilkS" user "Ref Des/Silkscreen Bottom")
		(1 "F.Mask" user "Board Geometry/Soldermask Top")
		(3 "B.Mask" user "Board Geometry/Soldermask Bottom")
		(17 "Dwgs.User" user "User.Drawings")
		(19 "Cmts.User" user "User.Comments")
		(21 "Eco1.User" user "User.Eco1")
		(23 "Eco2.User" user "User.Eco2")
		(25 "Edge.Cuts" user "Board Geometry/Outline")
		(27 "Margin" user)
		(31 "F.CrtYd" user "Package Geometry/Place Bound Top")
		(29 "B.CrtYd" user "Package Geometry/Place Bound Bottom")
		(35 "F.Fab" user "Ref Des/Assembly Top")
		(33 "B.Fab" user "Ref Des/Assembly Bottom")
	)
	(footprint ""
		(layer "F.Cu")
		(at 193.90868 -359.349548 180)
		(property "Reference" "R627"
			(at 0 0 180)
			(layer "F.SilkS")
			(hide yes)
			(effects
				(font
					(size 1.27 1.27)
				)
			)
		)
		(property "Value" ""
			(at 0 0 180)
			(layer "F.Fab")
			(effects
				(font
					(size 1.27 1.27)
				)
			)
		)
		(duplicate_pad_numbers_are_jumpers no)
		(fp_line
			(start 0.7874 0.4064)
			(end -0.7874 0.4064)
			(stroke
				(width 0.1524)
				(type default)
			)
			(layer "F.SilkS")
		)
		(fp_line
			(start 0.7874 -0.4064)
			(end 0.7874 0.4064)
			(stroke
				(width 0.1524)
				(type default)
			)
			(layer "F.SilkS")
		)
		(fp_line
			(start -0.7874 0.4064)
			(end -0.7874 -0.4064)
			(stroke
				(width 0.1524)
				(type default)
			)
			(layer "F.SilkS")
		)
		(fp_line
			(start -0.7874 -0.4064)
			(end 0.7874 -0.4064)
			(stroke
				(width 0.1524)
				(type default)
			)
			(layer "F.SilkS")
		)
		(fp_line
			(start 0.67945 0.3048)
			(end 0.120396 0.3048)
			(stroke
				(width 0.1)
				(type default)
			)
			(layer "F.Fab")
		)
		(fp_line
			(start 0.67945 -0.3048)
			(end 0.67945 0.3048)
			(stroke
				(width 0.1)
				(type default)
			)
			(layer "F.Fab")
		)
		(fp_line
			(start 0.12065 -0.2794)
			(end 0.12065 -0.3048)
			(stroke
				(width 0.1)
				(type default)
			)
			(layer "F.Fab")
		)
		(fp_line
			(start 0.12065 -0.3048)
			(end 0.67945 -0.3048)
			(stroke
				(width 0.1)
				(type default)
			)
			(layer "F.Fab")
		)
		(fp_line
			(start 0.120396 0.3048)
			(end 0.120396 0.2794)
			(stroke
				(width 0.1)
				(type default)
			)
			(layer "F.Fab")
		)
		(fp_line
			(start 0.120396 0.2794)
			(end -0.12065 0.2794)
			(stroke
				(width 0.1)
				(type default)
			)
			(layer "F.Fab")
		)
		(fp_line
			(start -0.12065 0.3048)
			(end -0.67945 0.3048)
			(stroke
				(width 0.1)
				(type default)
			)
			(layer "F.Fab")
		)
		(fp_line
			(start -0.12065 0.2794)
			(end -0.12065 0.3048)
			(stroke
				(width 0.1)
				(type default)
			)
			(layer "F.Fab")
		)
		(fp_line
			(start -0.12065 -0.2794)
			(end 0.12065 -0.2794)
			(stroke
				(width 0.1)
				(type default)
			)
			(layer "F.Fab")
		)
		(fp_line
			(start -0.12065 -0.305054)
			(end -0.12065 -0.2794)
			(stroke
				(width 0.1)
				(type default)
			)
			(layer "F.Fab")
		)
		(fp_line
			(start -0.67945 0.3048)
			(end -0.67945 -0.305054)
			(stroke
				(width 0.1)
				(type default)
			)
			(layer "F.Fab")
		)
		(fp_line
			(start -0.67945 -0.305054)
			(end -0.12065 -0.305054)
			(stroke
				(width 0.1)
				(type default)
			)
			(layer "F.Fab")
		)
		(pad "1" smd circle
			(at -0.40005 0 180)
			(size 0 0)
			(layers "F.Cu" "F.Mask" "F.Paste")
			(net "P3V3_AUX")
		)
		(pad "2" smd circle
			(at 0.40005 0 180)
			(size 0 0)
			(layers "F.Cu" "F.Mask" "F.Paste")
			(net "PD_PIROM_CPU1_ADDR1")
		)
	)
	(footprint ""
		(layer "F.Cu")
		(at 209.070956 -30.276292 90)
		(property "Reference" "R3624"
			(at 0 0 90)
			(layer "F.SilkS")
			(hide yes)
			(effects
				(font
					(size 1.27 1.27)
				)
			)
		)
		(property "Value" ""
			(at 0 0 90)
			(layer "F.Fab")
			(effects
				(font
					(size 1.27 1.27)
				)
			)
		)
		(duplicate_pad_numbers_are_jumpers no)
		(fp_line
			(start 0.7874 -0.4064)
			(end 0.7874 0.4064)
			(stroke
				(width 0.1524)
				(type default)
			)
			(layer "F.SilkS")
		)
		(fp_line
			(start -0.7874 -0.4064)
			(end 0.7874 -0.4064)
			(stroke
				(width 0.1524)
				(type default)
			)
			(layer "F.SilkS")
		)
		(fp_line
			(start 0.7874 0.4064)
			(end -0.7874 0.4064)
			(stroke
				(width 0.1524)
				(type default)
			)
			(layer "F.SilkS")
		)
		(fp_line
			(start -0.7874 0.4064)
			(end -0.7874 -0.4064)
			(stroke
				(width 0.1524)
				(type default)
			)
			(layer "F.SilkS")
		)
		(fp_line
			(start -0.12065 -0.305054)
			(end -0.12065 -0.2794)
			(stroke
				(width 0.1)
				(type default)
			)
			(layer "F.Fab")
		)
		(fp_line
			(start -0.67945 -0.305054)
			(end -0.12065 -0.305054)
			(stroke
				(width 0.1)
				(type default)
			)
			(layer "F.Fab")
		)
		(fp_line
			(start 0.67945 -0.3048)
			(end 0.67945 0.3048)
			(stroke
				(width 0.1)
				(type default)
			)
			(layer "F.Fab")
		)
		(fp_line
			(start 0.12065 -0.3048)
			(end 0.67945 -0.3048)
			(stroke
				(width 0.1)
				(type default)
			)
			(layer "F.Fab")
		)
		(fp_line
			(start 0.12065 -0.2794)
			(end 0.12065 -0.3048)
			(stroke
				(width 0.1)
				(type default)
			)
			(layer "F.Fab")
		)
		(fp_line
			(start -0.12065 -0.2794)
			(end 0.12065 -0.2794)
			(stroke
				(width 0.1)
				(type default)
			)
			(layer "F.Fab")
		)
		(fp_line
			(start 0.120396 0.2794)
			(end -0.12065 0.2794)
			(stroke
				(width 0.1)
				(type default)
			)
			(layer "F.Fab")
		)
		(fp_line
			(start -0.12065 0.2794)
			(end -0.12065 0.3048)
			(stroke
				(width 0.1)
				(type default)
			)
			(layer "F.Fab")
		)
		(fp_line
			(start 0.67945 0.3048)
			(end 0.120396 0.3048)
			(stroke
				(width 0.1)
				(type default)
			)
			(layer "F.Fab")
		)
		(fp_line
			(start 0.120396 0.3048)
			(end 0.120396 0.2794)
			(stroke
				(width 0.1)
				(type default)
			)
			(layer "F.Fab")
		)
		(fp_line
			(start -0.12065 0.3048)
			(end -0.67945 0.3048)
			(stroke
				(width 0.1)
				(type default)
			)
			(layer "F.Fab")
		)
		(fp_line
			(start -0.67945 0.3048)
			(end -0.67945 -0.305054)
			(stroke
				(width 0.1)
				(type default)
			)
			(layer "F.Fab")
		)
		(pad "1" smd circle
			(at -0.40005 0 90)
			(size 0 0)
			(layers "F.Cu" "F.Mask" "F.Paste")
			(net "P3V3_AUX")
		)
		(pad "2" smd circle
			(at 0.40005 0 90)
			(size 0 0)
			(layers "F.Cu" "F.Mask" "F.Paste")
			(net "INA230_5_A1")
		)
	)
)
